FILE_TYPE = MACRO_DRAWING;
SET COLOR_WIRE YELLOW;
SET COLOR_PROP ORANGE;
SET COLOR_DOT WHITE;
SET COLOR_ARC YELLOW;
SET COLOR_BODY GREEN;
SET COLOR_NOTE PURPLE;
SET PROP_DISPLAY VALUE;
SET PAGE_NUMBER P167;
FORCEADD Q_CAP..1
(-7700 4625);
FORCEPROP 1 LAST LOCATION PC126
J 0
(-7650 4725);
DISPLAY 0.489362 (-7650 4725);
PAINT SKYBLUE (-7650 4725);
FORCEPROP 0 LAST SEC 1
J 0
(-7650 4750);
DISPLAY 0.680851 (-7650 4750);
PAINT MONO (-7650 4750);
DISPLAY INVISIBLE (-7650 4750);
FORCEPROP 1 LASTPIN (-7700 4725) $PN 1
J 0
(-7690 4705);
DISPLAY 0.489362 (-7690 4705);
PAINT MONO (-7690 4705);
FORCEPROP 1 LASTPIN (-7700 4525) $PN 2
J 0
(-7690 4505);
DISPLAY 0.489362 (-7690 4505);
PAINT MONO (-7690 4505);
FORCEPROP 1 LAST MATERIAL X7R
J 0
(-7650 4525);
DISPLAY 0.489362 (-7650 4525);
PAINT SKYBLUE (-7650 4525);
FORCEPROP 1 LAST TOLERANCE 10%
J 0
(-7650 4575);
DISPLAY 0.489362 (-7650 4575);
PAINT SKYBLUE (-7650 4575);
FORCEPROP 1 LAST VALUE 0.1UF
J 0
(-7650 4675);
DISPLAY 0.489362 (-7650 4675);
PAINT SKYBLUE (-7650 4675);
FORCEPROP 1 LAST PART_NUMBER CH4104K1B00
J 0
(-7650 4475);
DISPLAY 0.489362 (-7650 4475);
PAINT SKYBLUE (-7650 4475);
FORCEPROP 1 LAST VOLTAGE 25V
J 0
(-7650 4625);
DISPLAY 0.489362 (-7650 4625);
PAINT SKYBLUE (-7650 4625);
FORCEPROP 1 LAST PACK_TYPE 0402
J 0
(-7650 4425);
DISPLAY 0.489362 (-7650 4425);
PAINT SKYBLUE (-7650 4425);
FORCEPROP 2 LAST CDS_LIB pure_quanta
J 0
(-7700 4625);
DISPLAY INVISIBLE (-7700 4625);
FORCEPROP 2 LAST SEC_TYPE 0402
J 0
(-7650 4825);
DISPLAY 1.021277 (-7650 4825);
DISPLAY INVISIBLE (-7650 4825);
FORCEPROP 1 LAST PATH I15
J 0
(-7650 4775);
DISPLAY 0.978723 (-7650 4775);
PAINT WHITE (-7650 4775);
DISPLAY INVISIBLE (-7650 4775);
FORCEADD MPQ8633AGLEC807Z..1
(-6700 3575);
FORCEPROP 1 LAST LOCATION PU55
J 0
(-6950 4547);
DISPLAY 0.489362 (-6950 4547);
PAINT SKYBLUE (-6950 4547);
FORCEPROP 0 LAST SEC 1
J 0
(-6950 4575);
DISPLAY 0.680851 (-6950 4575);
PAINT MONO (-6950 4575);
DISPLAY INVISIBLE (-6950 4575);
FORCEPROP 0 LASTPIN (-6300 2900) $PN 2
J 0
(-6290 2910);
DISPLAY 0.489362 (-6290 2910);
PAINT MONO (-6290 2910);
FORCEPROP 0 LASTPIN (-6300 4050) $PN 1
J 0
(-6290 4060);
DISPLAY 0.489362 (-6290 4060);
PAINT MONO (-6290 4060);
FORCEPROP 0 LASTPIN (-7100 2950) $PN 3
J 2
(-7110 2960);
DISPLAY 0.489362 (-7110 2960);
PAINT MONO (-7110 2960);
FORCEPROP 0 LASTPIN (-7100 3750) $PN 8
J 2
(-7110 3760);
DISPLAY 0.489362 (-7110 3760);
PAINT MONO (-7110 3760);
FORCEPROP 0 LASTPIN (-6300 3300) $PN 7
J 0
(-6290 3310);
DISPLAY 0.489362 (-6290 3310);
PAINT MONO (-6290 3310);
FORCEPROP 0 LASTPIN (-7100 3550) $PN 4
J 2
(-7110 3560);
DISPLAY 0.489362 (-7110 3560);
PAINT MONO (-7110 3560);
FORCEPROP 0 LASTPIN (-6300 2950) $PN 11_18
J 0
(-6290 2960);
DISPLAY 0.489362 (-6290 2960);
PAINT MONO (-6290 2960);
FORCEPROP 0 LASTPIN (-6300 4250) $PN 9
J 0
(-6290 4260);
DISPLAY 0.489362 (-6290 4260);
PAINT MONO (-6290 4260);
FORCEPROP 0 LASTPIN (-6300 3150) $PN 6
J 0
(-6290 3160);
DISPLAY 0.489362 (-6290 3160);
PAINT MONO (-6290 3160);
FORCEPROP 0 LASTPIN (-6300 3750) $PN 20
J 0
(-6290 3760);
DISPLAY 0.489362 (-6290 3760);
PAINT MONO (-6290 3760);
FORCEPROP 0 LASTPIN (-6300 3050) $PN 5
J 0
(-6290 3060);
DISPLAY 0.489362 (-6290 3060);
PAINT MONO (-6290 3060);
FORCEPROP 0 LASTPIN (-7100 3300) $PN 19
J 2
(-7110 3310);
DISPLAY 0.489362 (-7110 3310);
PAINT MONO (-7110 3310);
FORCEPROP 0 LASTPIN (-7100 4250) $PN 10
J 2
(-7110 4260);
DISPLAY 0.489362 (-7110 4260);
PAINT MONO (-7110 4260);
FORCEPROP 0 LASTPIN (-7100 4200) $PN 21
J 2
(-7110 4210);
DISPLAY 0.489362 (-7110 4210);
PAINT MONO (-7110 4210);
FORCEPROP 1 LAST MATERIAL IC
J 0
(-6947 4340);
DISPLAY 0.489362 (-6947 4340);
PAINT SKYBLUE (-6947 4340);
FORCEPROP 2 LAST VALUE MPQ8633AGLE-C807-Z
J 0
(-6953 4483);
DISPLAY 0.489362 (-6953 4483);
PAINT SKYBLUE (-6953 4483);
FORCEPROP 1 LAST PART_NUMBER AL008633007
J 0
(-6950 4400);
DISPLAY 0.489362 (-6950 4400);
PAINT SKYBLUE (-6950 4400);
FORCEPROP 2 LAST CDS_LIB pure_quanta
J 0
(-6700 3575);
DISPLAY INVISIBLE (-6700 3575);
FORCEPROP 1 LAST CDS_LMAN_SYM_OUTLINE -250,725,250,-725
J 0
(-6700 3575);
DISPLAY 0.468085 (-6700 3575);
PAINT GREEN (-6700 3575);
DISPLAY INVISIBLE (-6700 3575);
FORCEPROP 0 LAST PART_TYPE SMLF
J 0
(-6925 4575);
DISPLAY 1.021277 (-6925 4575);
DISPLAY INVISIBLE (-6925 4575);
FORCEPROP 1 LAST NEEDS_NO_SIZE TRUE
J 0
(-6700 3575);
DISPLAY 0.723404 (-6700 3575);
PAINT GREEN (-6700 3575);
DISPLAY INVISIBLE (-6700 3575);
FORCEPROP 2 LAST SEC_TYPE 
J 0
(-6950 4575);
DISPLAY 1.021277 (-6950 4575);
DISPLAY INVISIBLE (-6950 4575);
FORCEPROP 1 LAST PATH I18
J 0
(-6700 3575);
DISPLAY 0.723404 (-6700 3575);
PAINT GREEN (-6700 3575);
DISPLAY INVISIBLE (-6700 3575);
FORCEADD Q_CAP..1
(-5950 2900);
FORCEPROP 1 LAST LOCATION PC127
J 0
(-5900 3000);
DISPLAY 0.489362 (-5900 3000);
PAINT SKYBLUE (-5900 3000);
FORCEPROP 0 LAST SEC 1
J 0
(-5900 3025);
DISPLAY 0.680851 (-5900 3025);
PAINT MONO (-5900 3025);
DISPLAY INVISIBLE (-5900 3025);
FORCEPROP 1 LASTPIN (-5950 3000) $PN 1
J 0
(-5940 2980);
DISPLAY 0.489362 (-5940 2980);
PAINT MONO (-5940 2980);
FORCEPROP 1 LASTPIN (-5950 2800) $PN 2
J 0
(-5940 2780);
DISPLAY 0.489362 (-5940 2780);
PAINT MONO (-5940 2780);
FORCEPROP 1 LAST MATERIAL X7R
J 0
(-5900 2800);
DISPLAY 0.489362 (-5900 2800);
PAINT SKYBLUE (-5900 2800);
FORCEPROP 1 LAST TOLERANCE 10%
J 0
(-5900 2850);
DISPLAY 0.489362 (-5900 2850);
PAINT SKYBLUE (-5900 2850);
FORCEPROP 1 LAST VALUE 0.1UF
J 0
(-5900 2950);
DISPLAY 0.489362 (-5900 2950);
PAINT SKYBLUE (-5900 2950);
FORCEPROP 1 LAST PART_NUMBER CH4104K1B00
J 0
(-5900 2750);
DISPLAY 0.489362 (-5900 2750);
PAINT SKYBLUE (-5900 2750);
FORCEPROP 1 LAST VOLTAGE 25V
J 0
(-5900 2900);
DISPLAY 0.489362 (-5900 2900);
PAINT SKYBLUE (-5900 2900);
FORCEPROP 1 LAST PACK_TYPE 0402
J 0
(-5900 2700);
DISPLAY 0.489362 (-5900 2700);
PAINT SKYBLUE (-5900 2700);
FORCEPROP 2 LAST CDS_LIB pure_quanta
J 0
(-5950 2900);
DISPLAY INVISIBLE (-5950 2900);
FORCEPROP 2 LAST SEC_TYPE 0402
J 0
(-5900 3100);
DISPLAY 1.021277 (-5900 3100);
DISPLAY INVISIBLE (-5900 3100);
FORCEPROP 1 LAST PATH I19
J 0
(-5900 3050);
DISPLAY 0.978723 (-5900 3050);
PAINT WHITE (-5900 3050);
DISPLAY INVISIBLE (-5900 3050);
FORCEADD UNIVERSAL_POWER..1
(-9800 5000);
FORCEPROP 3 LASTPIN (-9800 4950) SIG_NAME P12V_STBY\g
J 0
(-9790 4960);
DISPLAY 0.659574 (-9790 4960);
PAINT MONO (-9790 4960);
DISPLAY INVISIBLE (-9790 4960);
FORCEPROP 1 LAST HDL_POWER P12V_STBY
J 1
(-9800 5050);
DISPLAY 0.489362 (-9800 5050);
PAINT GREEN (-9800 5050);
FORCEPROP 2 LAST CDS_LIB pure_quanta_power
J 0
(-9800 5000);
DISPLAY INVISIBLE (-9800 5000);
FORCEPROP 1 LAST PATH I2
J 0
(-9750 5025);
DISPLAY 0.872340 (-9750 5025);
PAINT AQUA (-9750 5025);
DISPLAY INVISIBLE (-9750 5025);
FORCEADD Q_RES..2
(-6200 4600);
FORCEPROP 1 LAST LOCATION PR453
J 0
(-6150 4725);
DISPLAY 0.489362 (-6150 4725);
PAINT SKYBLUE (-6150 4725);
FORCEPROP 0 LAST SEC 1
J 0
(-6150 4750);
DISPLAY 0.680851 (-6150 4750);
PAINT MONO (-6150 4750);
DISPLAY INVISIBLE (-6150 4750);
FORCEPROP 1 LASTPIN (-6200 4700) $PN 1
J 0
(-6195 4662);
DISPLAY 0.489362 (-6195 4662);
PAINT MONO (-6195 4662);
FORCEPROP 1 LASTPIN (-6200 4500) $PN 2
J 0
(-6195 4510);
DISPLAY 0.489362 (-6195 4510);
PAINT MONO (-6195 4510);
FORCEPROP 1 LAST WATTAGE 1/16W
J 0
(-6150 4575);
DISPLAY 0.489362 (-6150 4575);
PAINT SKYBLUE (-6150 4575);
FORCEPROP 1 LAST TOLERANCE 5%
J 0
(-6150 4625);
DISPLAY 0.489362 (-6150 4625);
PAINT SKYBLUE (-6150 4625);
FORCEPROP 1 LAST VALUE 10K
J 0
(-6150 4675);
DISPLAY 0.489362 (-6150 4675);
PAINT SKYBLUE (-6150 4675);
FORCEPROP 1 LAST PART_NUMBER TMP_QCS31002JB28
J 0
(-6150 4525);
DISPLAY 0.489362 (-6150 4525);
PAINT SKYBLUE (-6150 4525);
FORCEPROP 1 LAST PACK_TYPE 0402LF
J 0
(-6150 4450);
DISPLAY 0.489362 (-6150 4450);
PAINT SKYBLUE (-6150 4450);
FORCEPROP 2 LAST CDS_LIB pure_quanta
J 0
(-6200 4600);
DISPLAY INVISIBLE (-6200 4600);
FORCEPROP 2 LAST SEC_TYPE 0402LF
J 0
(-6150 4825);
DISPLAY 1.021277 (-6150 4825);
DISPLAY INVISIBLE (-6150 4825);
FORCEPROP 1 LAST PATH I21
J 0
(-6150 4775);
DISPLAY 0.978723 (-6150 4775);
PAINT WHITE (-6150 4775);
DISPLAY INVISIBLE (-6150 4775);
FORCEPROP 1 LAST MATERIAL CHIP
J 0
(-6160 4525);
DISPLAY 0.978723 (-6160 4525);
PAINT SKYBLUE (-6160 4525);
DISPLAY INVISIBLE (-6160 4525);
FORCEADD Q_CAP..1
(-5600 3900);
FORCEPROP 1 LAST LOCATION PC128
J 0
(-5550 4025);
DISPLAY 0.489362 (-5550 4025);
PAINT SKYBLUE (-5550 4025);
FORCEPROP 0 LAST SEC 1
J 0
(-5550 4050);
DISPLAY 0.680851 (-5550 4050);
PAINT MONO (-5550 4050);
DISPLAY INVISIBLE (-5550 4050);
FORCEPROP 1 LASTPIN (-5600 4000) $PN 1
J 0
(-5590 3980);
DISPLAY 0.489362 (-5590 3980);
PAINT MONO (-5590 3980);
FORCEPROP 1 LASTPIN (-5600 3800) $PN 2
J 0
(-5590 3780);
DISPLAY 0.489362 (-5590 3780);
PAINT MONO (-5590 3780);
FORCEPROP 1 LAST MATERIAL X7R
J 0
(-5550 3875);
DISPLAY 0.489362 (-5550 3875);
PAINT SKYBLUE (-5550 3875);
FORCEPROP 1 LAST VALUE 0.1UF
J 0
(-5550 3975);
DISPLAY 0.489362 (-5550 3975);
PAINT SKYBLUE (-5550 3975);
FORCEPROP 1 LAST PART_NUMBER CH4104K1B00
J 0
(-5550 3825);
DISPLAY 0.489362 (-5550 3825);
PAINT SKYBLUE (-5550 3825);
FORCEPROP 1 LAST VOLTAGE 25V
J 0
(-5550 3925);
DISPLAY 0.489362 (-5550 3925);
PAINT SKYBLUE (-5550 3925);
FORCEPROP 1 LAST PACK_TYPE 0402
J 0
(-5550 3775);
DISPLAY 0.489362 (-5550 3775);
PAINT SKYBLUE (-5550 3775);
FORCEPROP 2 LAST CDS_LIB pure_quanta
J 0
(-5600 3900);
DISPLAY INVISIBLE (-5600 3900);
FORCEPROP 2 LAST SEC_TYPE 0402
J 0
(-5550 4100);
DISPLAY 1.021277 (-5550 4100);
DISPLAY INVISIBLE (-5550 4100);
FORCEPROP 1 LAST PATH I22
J 0
(-5550 4050);
DISPLAY 0.978723 (-5550 4050);
PAINT WHITE (-5550 4050);
DISPLAY INVISIBLE (-5550 4050);
FORCEPROP 1 LAST TOLERANCE 10%
J 0
(-5550 3850);
DISPLAY 0.978723 (-5550 3850);
PAINT SKYBLUE (-5550 3850);
DISPLAY INVISIBLE (-5550 3850);
FORCEADD UNIVERSAL_POWER..1
R 2
(-6200 4900);
FORCEPROP 3 LASTPIN (-6200 4850) SIG_NAME PVDD_33_S5_VCC\g
J 0
(-6190 4860);
DISPLAY 0.659574 (-6190 4860);
PAINT MONO (-6190 4860);
DISPLAY INVISIBLE (-6190 4860);
FORCEPROP 1 LAST HDL_POWER PVDD_33_S5_VCC
J 1
(-6200 4950);
DISPLAY 0.489362 (-6200 4950);
PAINT GREEN (-6200 4950);
FORCEPROP 2 LAST CDS_LIB pure_quanta_power
J 0
(-6200 4900);
DISPLAY INVISIBLE (-6200 4900);
FORCEPROP 1 LAST PATH I24
J 2
(-6250 4925);
DISPLAY 0.872340 (-6250 4925);
PAINT AQUA (-6250 4925);
DISPLAY INVISIBLE (-6250 4925);
FORCEADD Q_RES..2
R 2
(-5000 2550);
FORCEPROP 1 LAST LOCATION PR454
J 0
(-4950 2650);
DISPLAY 0.489362 (-4950 2650);
PAINT SKYBLUE (-4950 2650);
FORCEPROP 0 LAST SEC 1
J 0
(-4950 2675);
DISPLAY 0.680851 (-4950 2675);
PAINT MONO (-4950 2675);
DISPLAY INVISIBLE (-4950 2675);
FORCEPROP 1 LASTPIN (-5000 2650) $PN 1
J 2
(-5005 2612);
DISPLAY 0.489362 (-5005 2612);
PAINT MONO (-5005 2612);
FORCEPROP 1 LASTPIN (-5000 2450) $PN 2
J 2
(-5005 2460);
DISPLAY 0.489362 (-5005 2460);
PAINT MONO (-5005 2460);
FORCEPROP 1 LAST WATTAGE 1/16W
J 0
(-4950 2500);
DISPLAY 0.489362 (-4950 2500);
PAINT SKYBLUE (-4950 2500);
FORCEPROP 1 LAST MATERIAL CHIP
J 0
(-4950 2450);
DISPLAY 0.489362 (-4950 2450);
PAINT SKYBLUE (-4950 2450);
FORCEPROP 1 LAST TOLERANCE 1%
J 2
(-4900 2550);
DISPLAY 0.489362 (-4900 2550);
PAINT SKYBLUE (-4900 2550);
FORCEPROP 1 LAST VALUE 12.4K
J 0
(-4950 2600);
DISPLAY 0.489362 (-4950 2600);
PAINT SKYBLUE (-4950 2600);
FORCEPROP 1 LAST PART_NUMBER CS31242FB13
J 0
(-4950 2400);
DISPLAY 0.489362 (-4950 2400);
PAINT SKYBLUE (-4950 2400);
FORCEPROP 1 LAST PACK_TYPE 0402LF
J 0
(-4950 2350);
DISPLAY 0.489362 (-4950 2350);
PAINT SKYBLUE (-4950 2350);
FORCEPROP 2 LAST CDS_LIB pure_quanta
J 0
(-5000 2550);
DISPLAY INVISIBLE (-5000 2550);
FORCEPROP 2 LAST SEC_TYPE 0402LF
J 0
(-5050 2775);
DISPLAY 1.021277 (-5050 2775);
DISPLAY INVISIBLE (-5050 2775);
FORCEPROP 1 LAST PATH I26
J 2
(-5050 2725);
DISPLAY 0.978723 (-5050 2725);
PAINT WHITE (-5050 2725);
DISPLAY INVISIBLE (-5050 2725);
FORCEADD Q_CAP..1
R 1
(-4050 2400);
FORCEPROP 1 LAST LOCATION PC132
J 0
(-4100 2450);
DISPLAY 0.489362 (-4100 2450);
PAINT SKYBLUE (-4100 2450);
FORCEPROP 0 LAST SEC 1
R 1
J 0
(-4100 2475);
DISPLAY 0.680851 (-4100 2475);
PAINT MONO (-4100 2475);
DISPLAY INVISIBLE (-4100 2475);
FORCEPROP 1 LASTPIN (-4150 2400) $PN 1
J 0
(-4130 2410);
DISPLAY 0.489362 (-4130 2410);
PAINT MONO (-4130 2410);
FORCEPROP 1 LASTPIN (-3950 2400) $PN 2
J 0
(-3985 2410);
DISPLAY 0.489362 (-3985 2410);
PAINT MONO (-3985 2410);
FORCEPROP 1 LAST MATERIAL NPO
J 0
(-3950 2350);
DISPLAY 0.489362 (-3950 2350);
PAINT SKYBLUE (-3950 2350);
FORCEPROP 1 LAST TOLERANCE 5%
J 0
(-4175 2425);
DISPLAY 0.489362 (-4175 2425);
PAINT SKYBLUE (-4175 2425);
FORCEPROP 1 LAST VALUE 100PF
J 0
(-4325 2425);
DISPLAY 0.489362 (-4325 2425);
PAINT SKYBLUE (-4325 2425);
FORCEPROP 1 LAST PART_NUMBER CH11006JB00
J 0
(-4375 2350);
DISPLAY 0.489362 (-4375 2350);
PAINT SKYBLUE (-4375 2350);
FORCEPROP 1 LAST VOLTAGE 50V
J 0
(-3925 2425);
DISPLAY 0.489362 (-3925 2425);
PAINT SKYBLUE (-3925 2425);
FORCEPROP 1 LAST PACK_TYPE 0402
J 0
(-3975 2300);
DISPLAY 0.489362 (-3975 2300);
PAINT SKYBLUE (-3975 2300);
FORCEPROP 2 LAST CDS_LIB pure_quanta
J 0
(-4050 2400);
DISPLAY INVISIBLE (-4050 2400);
FORCEPROP 2 LAST SEC_TYPE 0402
J 0
(-4100 2475);
DISPLAY 1.021277 (-4100 2475);
DISPLAY INVISIBLE (-4100 2475);
FORCEPROP 1 LAST PATH I27
R 1
J 0
(-4200 2450);
DISPLAY 0.978723 (-4200 2450);
PAINT WHITE (-4200 2450);
DISPLAY INVISIBLE (-4200 2450);
FORCEADD Q_RES..1
(-4050 2800);
FORCEPROP 1 LAST LOCATION PR455
J 0
(-4075 2850);
DISPLAY 0.489362 (-4075 2850);
PAINT SKYBLUE (-4075 2850);
FORCEPROP 0 LAST SEC 1
J 0
(-4075 2875);
DISPLAY 0.680851 (-4075 2875);
PAINT MONO (-4075 2875);
DISPLAY INVISIBLE (-4075 2875);
FORCEPROP 1 LASTPIN (-4150 2800) $PN 1
J 0
(-4138 2812);
DISPLAY 0.489362 (-4138 2812);
PAINT MONO (-4138 2812);
FORCEPROP 1 LASTPIN (-3950 2800) $PN 2
J 0
(-3988 2812);
DISPLAY 0.489362 (-3988 2812);
PAINT MONO (-3988 2812);
FORCEPROP 1 LAST WATTAGE 1/16W
J 2
(-3850 2825);
DISPLAY 0.489362 (-3850 2825);
PAINT SKYBLUE (-3850 2825);
FORCEPROP 1 LAST MATERIAL CHIP
J 0
(-3950 2750);
DISPLAY 0.489362 (-3950 2750);
PAINT SKYBLUE (-3950 2750);
FORCEPROP 1 LAST TOLERANCE 1%
J 0
(-4200 2825);
DISPLAY 0.489362 (-4200 2825);
PAINT SKYBLUE (-4200 2825);
FORCEPROP 1 LAST VALUE 56K
J 2
(-4225 2825);
DISPLAY 0.489362 (-4225 2825);
PAINT SKYBLUE (-4225 2825);
FORCEPROP 1 LAST PART_NUMBER TMP_QCS35602FB11
J 0
(-4425 2750);
DISPLAY 0.489362 (-4425 2750);
PAINT SKYBLUE (-4425 2750);
FORCEPROP 1 LAST PACK_TYPE 0402LF
J 0
(-3975 2700);
DISPLAY 0.489362 (-3975 2700);
PAINT SKYBLUE (-3975 2700);
FORCEPROP 2 LAST CDS_LIB pure_quanta
J 0
(-4050 2800);
DISPLAY INVISIBLE (-4050 2800);
FORCEPROP 2 LAST SEC_TYPE 0402LF
J 0
(-4100 3000);
DISPLAY 1.021277 (-4100 3000);
DISPLAY INVISIBLE (-4100 3000);
FORCEPROP 1 LAST PATH I29
J 0
(-4100 2950);
DISPLAY 0.978723 (-4100 2950);
PAINT WHITE (-4100 2950);
DISPLAY INVISIBLE (-4100 2950);
FORCEADD Q_CAP..1
(-4400 3450);
FORCEPROP 1 LAST LOCATION PC129
J 0
(-4350 3550);
DISPLAY 0.489362 (-4350 3550);
PAINT SKYBLUE (-4350 3550);
FORCEPROP 2 LAST SEC 1
J 0
(-4350 3650);
DISPLAY 0.680851 (-4350 3650);
PAINT MONO (-4350 3650);
DISPLAY INVISIBLE (-4350 3650);
FORCEPROP 1 LASTPIN (-4400 3550) $PN 1
J 0
(-4390 3530);
DISPLAY 0.489362 (-4390 3530);
PAINT MONO (-4390 3530);
FORCEPROP 1 LASTPIN (-4400 3350) $PN 2
J 0
(-4390 3330);
DISPLAY 0.489362 (-4390 3330);
PAINT MONO (-4390 3330);
FORCEPROP 1 LAST MATERIAL X6S
J 0
(-4350 3350);
DISPLAY 0.489362 (-4350 3350);
PAINT SKYBLUE (-4350 3350);
FORCEPROP 1 LAST TOLERANCE 20%
J 0
(-4350 3400);
DISPLAY 0.489362 (-4350 3400);
PAINT SKYBLUE (-4350 3400);
FORCEPROP 1 LAST VALUE 22UF
J 0
(-4350 3500);
DISPLAY 0.489362 (-4350 3500);
PAINT SKYBLUE (-4350 3500);
FORCEPROP 1 LAST VOLTAGE 16V
J 0
(-4350 3450);
DISPLAY 0.489362 (-4350 3450);
PAINT SKYBLUE (-4350 3450);
FORCEPROP 1 LAST PACK_TYPE C0805
J 0
(-4350 3300);
DISPLAY 0.489362 (-4350 3300);
PAINT SKYBLUE (-4350 3300);
FORCEPROP 2 LAST SEC_TYPE C0805
J 0
(-4350 3650);
DISPLAY 1.021277 (-4350 3650);
DISPLAY INVISIBLE (-4350 3650);
FORCEPROP 2 LAST CDS_LIB pure_quanta
J 0
(-4400 3450);
DISPLAY INVISIBLE (-4400 3450);
FORCEPROP 1 LAST PATH I34
J 0
(-4350 3600);
DISPLAY 0.978723 (-4350 3600);
PAINT WHITE (-4350 3600);
DISPLAY INVISIBLE (-4350 3600);
FORCEPROP 1 LAST PART_NUMBER CH6223MEA00
J 0
(-4350 3300);
DISPLAY 0.978723 (-4350 3300);
PAINT SKYBLUE (-4350 3300);
DISPLAY INVISIBLE (-4350 3300);
FORCEADD Q_CAP..1
(-4100 3450);
FORCEPROP 1 LAST LOCATION PC130
J 0
(-4050 3550);
DISPLAY 0.489362 (-4050 3550);
PAINT SKYBLUE (-4050 3550);
FORCEPROP 2 LAST SEC 1
J 0
(-4050 3650);
DISPLAY 0.680851 (-4050 3650);
PAINT MONO (-4050 3650);
DISPLAY INVISIBLE (-4050 3650);
FORCEPROP 1 LASTPIN (-4100 3550) $PN 1
J 0
(-4090 3530);
DISPLAY 0.489362 (-4090 3530);
PAINT MONO (-4090 3530);
FORCEPROP 1 LASTPIN (-4100 3350) $PN 2
J 0
(-4090 3330);
DISPLAY 0.489362 (-4090 3330);
PAINT MONO (-4090 3330);
FORCEPROP 1 LAST MATERIAL X6S
J 0
(-4050 3350);
DISPLAY 0.489362 (-4050 3350);
PAINT SKYBLUE (-4050 3350);
FORCEPROP 1 LAST TOLERANCE 20%
J 0
(-4050 3400);
DISPLAY 0.489362 (-4050 3400);
PAINT SKYBLUE (-4050 3400);
FORCEPROP 1 LAST VALUE 22UF
J 0
(-4050 3500);
DISPLAY 0.489362 (-4050 3500);
PAINT SKYBLUE (-4050 3500);
FORCEPROP 1 LAST VOLTAGE 16V
J 0
(-4050 3450);
DISPLAY 0.489362 (-4050 3450);
PAINT SKYBLUE (-4050 3450);
FORCEPROP 1 LAST PACK_TYPE C0805
J 0
(-4050 3300);
DISPLAY 0.489362 (-4050 3300);
PAINT SKYBLUE (-4050 3300);
FORCEPROP 2 LAST SEC_TYPE C0805
J 0
(-4050 3650);
DISPLAY 1.021277 (-4050 3650);
DISPLAY INVISIBLE (-4050 3650);
FORCEPROP 2 LAST CDS_LIB pure_quanta
J 0
(-4100 3450);
DISPLAY INVISIBLE (-4100 3450);
FORCEPROP 1 LAST PATH I35
J 0
(-4050 3600);
DISPLAY 0.978723 (-4050 3600);
PAINT WHITE (-4050 3600);
DISPLAY INVISIBLE (-4050 3600);
FORCEPROP 1 LAST PART_NUMBER CH6223MEA00
J 0
(-4050 3300);
DISPLAY 0.978723 (-4050 3300);
PAINT SKYBLUE (-4050 3300);
DISPLAY INVISIBLE (-4050 3300);
FORCEADD Q_CAP..1
(-3800 3450);
FORCEPROP 1 LAST LOCATION PC134
J 0
(-3750 3550);
DISPLAY 0.489362 (-3750 3550);
PAINT SKYBLUE (-3750 3550);
FORCEPROP 2 LAST SEC 1
J 0
(-3750 3650);
DISPLAY 0.680851 (-3750 3650);
PAINT MONO (-3750 3650);
DISPLAY INVISIBLE (-3750 3650);
FORCEPROP 1 LASTPIN (-3800 3550) $PN 1
J 0
(-3790 3530);
DISPLAY 0.489362 (-3790 3530);
PAINT MONO (-3790 3530);
FORCEPROP 1 LASTPIN (-3800 3350) $PN 2
J 0
(-3790 3330);
DISPLAY 0.489362 (-3790 3330);
PAINT MONO (-3790 3330);
FORCEPROP 1 LAST MATERIAL X6S
J 0
(-3750 3350);
DISPLAY 0.489362 (-3750 3350);
PAINT SKYBLUE (-3750 3350);
FORCEPROP 1 LAST TOLERANCE 20%
J 0
(-3750 3400);
DISPLAY 0.489362 (-3750 3400);
PAINT SKYBLUE (-3750 3400);
FORCEPROP 1 LAST VALUE 22UF
J 0
(-3750 3500);
DISPLAY 0.489362 (-3750 3500);
PAINT SKYBLUE (-3750 3500);
FORCEPROP 1 LAST VOLTAGE 16V
J 0
(-3750 3450);
DISPLAY 0.489362 (-3750 3450);
PAINT SKYBLUE (-3750 3450);
FORCEPROP 1 LAST PACK_TYPE C0805
J 0
(-3750 3300);
DISPLAY 0.489362 (-3750 3300);
PAINT SKYBLUE (-3750 3300);
FORCEPROP 2 LAST SEC_TYPE C0805
J 0
(-3750 3650);
DISPLAY 1.021277 (-3750 3650);
DISPLAY INVISIBLE (-3750 3650);
FORCEPROP 2 LAST CDS_LIB pure_quanta
J 0
(-3800 3450);
DISPLAY INVISIBLE (-3800 3450);
FORCEPROP 1 LAST PATH I36
J 0
(-3750 3600);
DISPLAY 0.978723 (-3750 3600);
PAINT WHITE (-3750 3600);
DISPLAY INVISIBLE (-3750 3600);
FORCEPROP 1 LAST PART_NUMBER CH6223MEA00
J 0
(-3750 3300);
DISPLAY 0.978723 (-3750 3300);
PAINT SKYBLUE (-3750 3300);
DISPLAY INVISIBLE (-3750 3300);
FORCEADD Q_CAP..1
(-3500 3450);
FORCEPROP 1 LAST LOCATION PC135
J 0
(-3450 3550);
DISPLAY 0.489362 (-3450 3550);
PAINT SKYBLUE (-3450 3550);
FORCEPROP 2 LAST SEC 1
J 0
(-3450 3650);
DISPLAY 0.680851 (-3450 3650);
PAINT MONO (-3450 3650);
DISPLAY INVISIBLE (-3450 3650);
FORCEPROP 1 LASTPIN (-3500 3550) $PN 1
J 0
(-3490 3530);
DISPLAY 0.489362 (-3490 3530);
PAINT MONO (-3490 3530);
FORCEPROP 1 LASTPIN (-3500 3350) $PN 2
J 0
(-3490 3330);
DISPLAY 0.489362 (-3490 3330);
PAINT MONO (-3490 3330);
FORCEPROP 1 LAST MATERIAL X6S
J 0
(-3450 3350);
DISPLAY 0.489362 (-3450 3350);
PAINT SKYBLUE (-3450 3350);
FORCEPROP 1 LAST TOLERANCE 20%
J 0
(-3450 3400);
DISPLAY 0.489362 (-3450 3400);
PAINT SKYBLUE (-3450 3400);
FORCEPROP 1 LAST VALUE 22UF
J 0
(-3450 3500);
DISPLAY 0.489362 (-3450 3500);
PAINT SKYBLUE (-3450 3500);
FORCEPROP 1 LAST PART_NUMBER CH6223MEA00
J 0
(-3450 3250);
DISPLAY 0.489362 (-3450 3250);
PAINT SKYBLUE (-3450 3250);
FORCEPROP 1 LAST VOLTAGE 16V
J 0
(-3450 3450);
DISPLAY 0.489362 (-3450 3450);
PAINT SKYBLUE (-3450 3450);
FORCEPROP 1 LAST PACK_TYPE C0805
J 0
(-3450 3300);
DISPLAY 0.489362 (-3450 3300);
PAINT SKYBLUE (-3450 3300);
FORCEPROP 2 LAST SEC_TYPE C0805
J 0
(-3450 3650);
DISPLAY 1.021277 (-3450 3650);
DISPLAY INVISIBLE (-3450 3650);
FORCEPROP 2 LAST CDS_LIB pure_quanta
J 0
(-3500 3450);
DISPLAY INVISIBLE (-3500 3450);
FORCEPROP 1 LAST PATH I37
J 0
(-3450 3600);
DISPLAY 0.978723 (-3450 3600);
PAINT WHITE (-3450 3600);
DISPLAY INVISIBLE (-3450 3600);
FORCEADD Q_CAP..1
(-3100 3450);
FORCEPROP 1 LAST LOCATION PC136
J 0
(-3050 3550);
DISPLAY 0.489362 (-3050 3550);
PAINT SKYBLUE (-3050 3550);
FORCEPROP 2 LAST SEC 1
J 0
(-3050 3650);
DISPLAY 0.680851 (-3050 3650);
PAINT MONO (-3050 3650);
DISPLAY INVISIBLE (-3050 3650);
FORCEPROP 1 LASTPIN (-3100 3550) $PN 1
J 0
(-3090 3530);
DISPLAY 0.489362 (-3090 3530);
PAINT MONO (-3090 3530);
FORCEPROP 1 LASTPIN (-3100 3350) $PN 2
J 0
(-3090 3330);
DISPLAY 0.489362 (-3090 3330);
PAINT MONO (-3090 3330);
FORCEPROP 1 LAST MATERIAL X7R
J 0
(-3050 3350);
DISPLAY 0.489362 (-3050 3350);
PAINT SKYBLUE (-3050 3350);
FORCEPROP 1 LAST TOLERANCE 10%
J 0
(-3050 3400);
DISPLAY 0.489362 (-3050 3400);
PAINT SKYBLUE (-3050 3400);
FORCEPROP 1 LAST VALUE 0.1UF
J 0
(-3050 3500);
DISPLAY 0.489362 (-3050 3500);
PAINT SKYBLUE (-3050 3500);
FORCEPROP 1 LAST PART_NUMBER CH4104K1B00
J 0
(-3050 3300);
DISPLAY 0.489362 (-3050 3300);
PAINT SKYBLUE (-3050 3300);
FORCEPROP 1 LAST VOLTAGE 25V
J 0
(-3050 3450);
DISPLAY 0.489362 (-3050 3450);
PAINT SKYBLUE (-3050 3450);
FORCEPROP 1 LAST PACK_TYPE 0402
J 0
(-3050 3250);
DISPLAY 0.489362 (-3050 3250);
PAINT SKYBLUE (-3050 3250);
FORCEPROP 2 LAST SEC_TYPE 0402
J 0
(-3050 3650);
DISPLAY 1.021277 (-3050 3650);
DISPLAY INVISIBLE (-3050 3650);
FORCEPROP 2 LAST CDS_LIB pure_quanta
J 0
(-3100 3450);
DISPLAY INVISIBLE (-3100 3450);
FORCEPROP 1 LAST PATH I39
J 0
(-3050 3600);
DISPLAY 0.978723 (-3050 3600);
PAINT WHITE (-3050 3600);
DISPLAY INVISIBLE (-3050 3600);
FORCEADD UNIVERSAL_POWER..1
(-2650 3900);
FORCEPROP 3 LASTPIN (-2650 3850) SIG_NAME PVDD_33_S5\g
J 0
(-2640 3860);
DISPLAY 0.659574 (-2640 3860);
PAINT MONO (-2640 3860);
DISPLAY INVISIBLE (-2640 3860);
FORCEPROP 1 LAST HDL_POWER PVDD_33_S5
J 1
(-2650 3950);
DISPLAY 0.489362 (-2650 3950);
PAINT GREEN (-2650 3950);
FORCEPROP 2 LAST CDS_LIB pure_quanta_power
J 0
(-2650 3900);
DISPLAY INVISIBLE (-2650 3900);
FORCEPROP 1 LAST PATH I40
J 0
(-2600 3925);
DISPLAY 0.872340 (-2600 3925);
PAINT AQUA (-2600 3925);
DISPLAY INVISIBLE (-2600 3925);
FORCEADD UNIVERSAL_GND..1
(-9000 4250);
FORCEPROP 3 LASTPIN (-9000 4300) SIG_NAME GND\g
J 0
(-8990 4310);
DISPLAY 0.659574 (-8990 4310);
PAINT MONO (-8990 4310);
DISPLAY INVISIBLE (-8990 4310);
FORCEPROP 2 LAST CDS_LIB pure_quanta_power
J 0
(-9000 4250);
DISPLAY INVISIBLE (-9000 4250);
FORCEPROP 1 LAST PATH I41
J 0
(-8925 4250);
DISPLAY 0.872340 (-8925 4250);
PAINT AQUA (-8925 4250);
DISPLAY INVISIBLE (-8925 4250);
FORCEPROP 1 LAST HDL_POWER GND
J 1
(-8975 4175);
DISPLAY 0.872340 (-8975 4175);
PAINT GREEN (-8975 4175);
DISPLAY INVISIBLE (-8975 4175);
FORCEADD UNIVERSAL_GND..1
(-7700 2450);
FORCEPROP 3 LASTPIN (-7700 2500) SIG_NAME GND\g
J 0
(-7690 2510);
DISPLAY 0.659574 (-7690 2510);
PAINT MONO (-7690 2510);
DISPLAY INVISIBLE (-7690 2510);
FORCEPROP 2 LAST CDS_LIB pure_quanta_power
J 0
(-7700 2450);
DISPLAY INVISIBLE (-7700 2450);
FORCEPROP 1 LAST PATH I44
J 0
(-7625 2450);
DISPLAY 0.872340 (-7625 2450);
PAINT AQUA (-7625 2450);
DISPLAY INVISIBLE (-7625 2450);
FORCEPROP 1 LAST HDL_POWER GND
J 1
(-7675 2375);
DISPLAY 0.872340 (-7675 2375);
PAINT GREEN (-7675 2375);
DISPLAY INVISIBLE (-7675 2375);
FORCEADD UNIVERSAL_GND..1
(-6200 2700);
FORCEPROP 3 LASTPIN (-6200 2750) SIG_NAME GND\g
J 0
(-6190 2760);
DISPLAY 0.659574 (-6190 2760);
PAINT MONO (-6190 2760);
DISPLAY INVISIBLE (-6190 2760);
FORCEPROP 2 LAST CDS_LIB pure_quanta_power
J 0
(-6200 2700);
DISPLAY INVISIBLE (-6200 2700);
FORCEPROP 1 LAST PATH I45
J 0
(-6125 2700);
DISPLAY 0.872340 (-6125 2700);
PAINT AQUA (-6125 2700);
DISPLAY INVISIBLE (-6125 2700);
FORCEPROP 1 LAST HDL_POWER GND
J 1
(-6175 2625);
DISPLAY 0.872340 (-6175 2625);
PAINT GREEN (-6175 2625);
DISPLAY INVISIBLE (-6175 2625);
FORCEADD UNIVERSAL_GND..1
(-5950 2700);
FORCEPROP 3 LASTPIN (-5950 2750) SIG_NAME GND\g
J 0
(-5940 2760);
DISPLAY 0.659574 (-5940 2760);
PAINT MONO (-5940 2760);
DISPLAY INVISIBLE (-5940 2760);
FORCEPROP 2 LAST CDS_LIB pure_quanta_power
J 0
(-5950 2700);
DISPLAY INVISIBLE (-5950 2700);
FORCEPROP 1 LAST PATH I46
J 0
(-5875 2700);
DISPLAY 0.872340 (-5875 2700);
PAINT AQUA (-5875 2700);
DISPLAY INVISIBLE (-5875 2700);
FORCEPROP 1 LAST HDL_POWER GND
J 1
(-5925 2625);
DISPLAY 0.872340 (-5925 2625);
PAINT GREEN (-5925 2625);
DISPLAY INVISIBLE (-5925 2625);
FORCEADD UNIVERSAL_GND..1
(-5600 2700);
FORCEPROP 3 LASTPIN (-5600 2750) SIG_NAME GND\g
J 0
(-5590 2760);
DISPLAY 0.659574 (-5590 2760);
PAINT MONO (-5590 2760);
DISPLAY INVISIBLE (-5590 2760);
FORCEPROP 2 LAST CDS_LIB pure_quanta_power
J 0
(-5600 2700);
DISPLAY INVISIBLE (-5600 2700);
FORCEPROP 1 LAST PATH I47
J 0
(-5525 2700);
DISPLAY 0.872340 (-5525 2700);
PAINT AQUA (-5525 2700);
DISPLAY INVISIBLE (-5525 2700);
FORCEPROP 1 LAST HDL_POWER GND
J 1
(-5575 2625);
DISPLAY 0.872340 (-5575 2625);
PAINT GREEN (-5575 2625);
DISPLAY INVISIBLE (-5575 2625);
FORCEADD UNIVERSAL_GND..1
(-5000 2275);
FORCEPROP 3 LASTPIN (-5000 2325) SIG_NAME GND\g
J 0
(-4990 2335);
DISPLAY 0.659574 (-4990 2335);
PAINT MONO (-4990 2335);
DISPLAY INVISIBLE (-4990 2335);
FORCEPROP 2 LAST CDS_LIB pure_quanta_power
J 0
(-5000 2275);
DISPLAY INVISIBLE (-5000 2275);
FORCEPROP 1 LAST PATH I48
J 0
(-4925 2275);
DISPLAY 0.872340 (-4925 2275);
PAINT AQUA (-4925 2275);
DISPLAY INVISIBLE (-4925 2275);
FORCEPROP 1 LAST HDL_POWER GND
J 1
(-4975 2200);
DISPLAY 0.872340 (-4975 2200);
PAINT GREEN (-4975 2200);
DISPLAY INVISIBLE (-4975 2200);
FORCEADD UNIVERSAL_GND..1
(-3100 3050);
FORCEPROP 3 LASTPIN (-3100 3100) SIG_NAME GND\g
J 0
(-3090 3110);
DISPLAY 0.659574 (-3090 3110);
PAINT MONO (-3090 3110);
DISPLAY INVISIBLE (-3090 3110);
FORCEPROP 2 LAST CDS_LIB pure_quanta_power
J 0
(-3100 3050);
DISPLAY INVISIBLE (-3100 3050);
FORCEPROP 1 LAST PATH I49
J 0
(-3025 3050);
DISPLAY 0.872340 (-3025 3050);
PAINT AQUA (-3025 3050);
DISPLAY INVISIBLE (-3025 3050);
FORCEPROP 1 LAST HDL_POWER GND
J 1
(-3075 2975);
DISPLAY 0.872340 (-3075 2975);
PAINT GREEN (-3075 2975);
DISPLAY INVISIBLE (-3075 2975);
FORCEADD Q_RES..2
(-7700 2725);
FORCEPROP 1 LAST LOCATION PR452
J 0
(-7655 2850);
DISPLAY 0.489362 (-7655 2850);
PAINT SKYBLUE (-7655 2850);
FORCEPROP 0 LAST SEC 1
J 0
(-7650 2875);
DISPLAY 0.680851 (-7650 2875);
PAINT MONO (-7650 2875);
DISPLAY INVISIBLE (-7650 2875);
FORCEPROP 1 LASTPIN (-7700 2825) $PN 1
J 0
(-7695 2787);
DISPLAY 0.489362 (-7695 2787);
PAINT MONO (-7695 2787);
FORCEPROP 1 LASTPIN (-7700 2625) $PN 2
J 0
(-7695 2635);
DISPLAY 0.489362 (-7695 2635);
PAINT MONO (-7695 2635);
FORCEPROP 1 LAST WATTAGE 1/16W
J 0
(-7660 2700);
DISPLAY 0.489362 (-7660 2700);
PAINT SKYBLUE (-7660 2700);
FORCEPROP 1 LAST MATERIAL CHIP
J 0
(-7660 2650);
DISPLAY 0.489362 (-7660 2650);
PAINT SKYBLUE (-7660 2650);
FORCEPROP 1 LAST TOLERANCE 1%
J 0
(-7655 2750);
DISPLAY 0.489362 (-7655 2750);
PAINT SKYBLUE (-7655 2750);
FORCEPROP 1 LAST VALUE 6.98K
J 0
(-7655 2800);
DISPLAY 0.489362 (-7655 2800);
PAINT SKYBLUE (-7655 2800);
FORCEPROP 1 LAST PART_NUMBER CS26982FB08
J 0
(-7660 2600);
DISPLAY 0.489362 (-7660 2600);
PAINT SKYBLUE (-7660 2600);
FORCEPROP 1 LAST PACK_TYPE 0402LF
J 0
(-7660 2550);
DISPLAY 0.489362 (-7660 2550);
PAINT SKYBLUE (-7660 2550);
FORCEPROP 2 LAST SEC_TYPE 0402LF
J 0
(-7650 2950);
DISPLAY 1.021277 (-7650 2950);
DISPLAY INVISIBLE (-7650 2950);
FORCEPROP 2 LAST CDS_LIB pure_quanta
J 0
(-7700 2725);
DISPLAY INVISIBLE (-7700 2725);
FORCEPROP 1 LAST PATH I5
J 0
(-7650 2900);
DISPLAY 0.978723 (-7650 2900);
PAINT WHITE (-7650 2900);
DISPLAY INVISIBLE (-7650 2900);
FORCEADD Q_INDUCTOR..1
(-9400 4825);
FORCEPROP 1 LAST LOCATION PL71
J 0
(-9525 4985);
DISPLAY 0.489362 (-9525 4985);
PAINT SKYBLUE (-9525 4985);
FORCEPROP 0 LAST SEC 1
J 0
(-9525 5100);
DISPLAY 0.680851 (-9525 5100);
PAINT MONO (-9525 5100);
DISPLAY INVISIBLE (-9525 5100);
FORCEPROP 0 LASTPIN (-9500 4800) $PN 1
J 2
(-9510 4810);
DISPLAY 0.489362 (-9510 4810);
PAINT MONO (-9510 4810);
FORCEPROP 0 LASTPIN (-9300 4800) $PN 2
J 0
(-9310 4810);
DISPLAY 0.489362 (-9310 4810);
PAINT MONO (-9310 4810);
FORCEPROP 1 LAST MATERIAL IND
J 0
(-9525 4880);
DISPLAY 0.489362 (-9525 4880);
PAINT SKYBLUE (-9525 4880);
FORCEPROP 2 LAST VALUE BLM18SN220TN1D/8000MA
J 0
(-9525 5025);
DISPLAY 0.489362 (-9525 5025);
PAINT SKYBLUE (-9525 5025);
FORCEPROP 1 LAST PART_NUMBER CX220TN1001
J 0
(-9525 4935);
DISPLAY 0.489362 (-9525 4935);
PAINT SKYBLUE (-9525 4935);
FORCEPROP 2 LAST PACK_TYPE SMLF
J 0
(-9525 5075);
DISPLAY 0.489362 (-9525 5075);
PAINT SKYBLUE (-9525 5075);
FORCEPROP 2 LAST CDS_LIB pure_quanta
J 0
(-9400 4825);
DISPLAY INVISIBLE (-9400 4825);
FORCEPROP 1 LAST NEEDS_NO_SIZE TRUE
J 0
(-9400 4825);
DISPLAY 0.468085 (-9400 4825);
PAINT GREEN (-9400 4825);
DISPLAY INVISIBLE (-9400 4825);
FORCEPROP 2 LAST SEC_TYPE SMLF
J 0
(-9525 5100);
DISPLAY 1.021277 (-9525 5100);
DISPLAY INVISIBLE (-9525 5100);
FORCEPROP 1 LAST PATH I50
J 0
(-9325 4880);
DISPLAY 0.723404 (-9325 4880);
PAINT GREEN (-9325 4880);
DISPLAY INVISIBLE (-9325 4880);
FORCEADD UNIVERSAL_GND..1
(-8275 2375);
FORCEPROP 3 LASTPIN (-8275 2425) SIG_NAME GND\g
J 0
(-8265 2435);
DISPLAY 0.659574 (-8265 2435);
PAINT MONO (-8265 2435);
DISPLAY INVISIBLE (-8265 2435);
FORCEPROP 2 LAST CDS_LIB pure_quanta_power
J 0
(-8275 2375);
DISPLAY INVISIBLE (-8275 2375);
FORCEPROP 1 LAST PATH I51
J 0
(-8200 2375);
DISPLAY 0.872340 (-8200 2375);
PAINT AQUA (-8200 2375);
DISPLAY INVISIBLE (-8200 2375);
FORCEPROP 1 LAST HDL_POWER GND
J 1
(-8250 2300);
DISPLAY 0.872340 (-8250 2300);
PAINT GREEN (-8250 2300);
DISPLAY INVISIBLE (-8250 2300);
FORCEADD Q_CAP..1
R 2
(-8275 2650);
FORCEPROP 1 LAST LOCATION PC118
J 0
(-8225 2790);
DISPLAY 0.489362 (-8225 2790);
PAINT SKYBLUE (-8225 2790);
FORCEPROP 0 LAST SEC 1
J 0
(-8225 2815);
DISPLAY 0.680851 (-8225 2815);
PAINT MONO (-8225 2815);
DISPLAY INVISIBLE (-8225 2815);
FORCEPROP 1 LASTPIN (-8275 2750) $PN 1
J 2
(-8235 2725);
DISPLAY 0.489362 (-8235 2725);
PAINT MONO (-8235 2725);
FORCEPROP 1 LASTPIN (-8275 2550) $PN 2
J 2
(-8235 2535);
DISPLAY 0.489362 (-8235 2535);
PAINT MONO (-8235 2535);
FORCEPROP 1 LAST MATERIAL X6S
J 0
(-8225 2581);
DISPLAY 0.489362 (-8225 2581);
PAINT SKYBLUE (-8225 2581);
FORCEPROP 1 LAST TOLERANCE 10%
J 0
(-8225 2630);
DISPLAY 0.489362 (-8225 2630);
PAINT SKYBLUE (-8225 2630);
FORCEPROP 1 LAST VALUE 1UF
J 0
(-8225 2728);
DISPLAY 0.489362 (-8225 2728);
PAINT SKYBLUE (-8225 2728);
FORCEPROP 1 LAST PART_NUMBER CH5104KEB02
J 0
(-8225 2483);
DISPLAY 0.489362 (-8225 2483);
PAINT SKYBLUE (-8225 2483);
FORCEPROP 1 LAST VOLTAGE 25V
J 0
(-8225 2679);
DISPLAY 0.489362 (-8225 2679);
PAINT SKYBLUE (-8225 2679);
FORCEPROP 1 LAST PACK_TYPE C0402
J 0
(-8225 2532);
DISPLAY 0.489362 (-8225 2532);
PAINT SKYBLUE (-8225 2532);
FORCEPROP 2 LAST SIGNAL_MODEL DEFAULT_CAPACITOR_100000PF_2_1
R 3
J 1
(-8345 2598);
DISPLAY 0.744681 (-8345 2598);
PAINT MONO (-8345 2598);
DISPLAY INVISIBLE (-8345 2598);
FORCEPROP 2 LAST CDS_LIB pure_quanta
J 0
(-8275 2650);
DISPLAY INVISIBLE (-8275 2650);
FORCEPROP 2 LAST SEC_TYPE C0402
J 0
(-8325 2865);
DISPLAY 1.021277 (-8325 2865);
DISPLAY INVISIBLE (-8325 2865);
FORCEPROP 1 LAST PATH I52
J 2
(-8325 2800);
DISPLAY 0.978723 (-8325 2800);
PAINT WHITE (-8325 2800);
DISPLAY INVISIBLE (-8325 2800);
FORCEPROP 2 LAST ROOM VR_DDR0_CTRL
R 3
J 1
(-8331 2611);
DISPLAY 0.744681 (-8331 2611);
PAINT RED (-8331 2611);
DISPLAY INVISIBLE (-8331 2611);
FORCEADD UNIVERSAL_POWER..1
(-8275 3200);
FORCEPROP 3 LASTPIN (-8275 3150) SIG_NAME PVDD_33_S5_VCC\g
J 0
(-8265 3160);
DISPLAY 0.659574 (-8265 3160);
PAINT MONO (-8265 3160);
DISPLAY INVISIBLE (-8265 3160);
FORCEPROP 1 LAST HDL_POWER PVDD_33_S5_VCC
J 1
(-8275 3250);
DISPLAY 0.489362 (-8275 3250);
PAINT GREEN (-8275 3250);
FORCEPROP 2 LAST CDS_LIB pure_quanta_power
J 0
(-8275 3200);
DISPLAY INVISIBLE (-8275 3200);
FORCEPROP 1 LAST PATH I53
J 0
(-8225 3225);
DISPLAY 0.872340 (-8225 3225);
PAINT AQUA (-8225 3225);
DISPLAY INVISIBLE (-8225 3225);
FORCEADD OFFPAGE..1
(-8600 3750);
FORCEPROP 2 LAST $XR0 80 
J 0
(-8851 3750);
DISPLAY 0.638298 (-8851 3750);
PAINT MONO (-8851 3750);
FORCEPROP 2 LAST PATH I54
J 0
(-8550 3825);
DISPLAY 0.680851 (-8550 3825);
DISPLAY INVISIBLE (-8550 3825);
FORCEPROP 1 LAST COMMENT_BODY TRUE
J 0
(-8475 3650);
DISPLAY 0.872340 (-8475 3650);
PAINT GREEN (-8475 3650);
DISPLAY INVISIBLE (-8475 3650);
FORCEPROP 1 LAST OFFPAGE TRUE
J 0
(-8275 3625);
DISPLAY 0.872340 (-8275 3625);
PAINT GREEN (-8275 3625);
DISPLAY INVISIBLE (-8275 3625);
FORCEPROP 2 LAST CDS_LIB standard
J 0
(-8600 3750);
DISPLAY INVISIBLE (-8600 3750);
FORCEADD Q_INDUCTOR..1
(-5000 3775);
FORCEPROP 1 LAST LOCATION PL72
J 0
(-5025 3800);
DISPLAY 0.489362 (-5025 3800);
PAINT SKYBLUE (-5025 3800);
FORCEPROP 0 LAST $SEC 1
J 0
(-4825 3825);
DISPLAY 0.680851 (-4825 3825);
PAINT MONO (-4825 3825);
DISPLAY INVISIBLE (-4825 3825);
FORCEPROP 0 LAST CDS_SEC 1
J 0
(-4825 3825);
DISPLAY 0.680851 (-4825 3825);
DISPLAY INVISIBLE (-4825 3825);
FORCEPROP 0 LASTPIN (-5100 3750) $PN 1
J 2
(-5110 3760);
DISPLAY 0.489362 (-5110 3760);
PAINT MONO (-5110 3760);
FORCEPROP 0 LASTPIN (-4900 3750) $PN 2
J 0
(-4890 3760);
DISPLAY 0.489362 (-4890 3760);
PAINT MONO (-4890 3760);
FORCEPROP 1 LAST MATERIAL IND
J 0
(-4800 3700);
DISPLAY 0.489362 (-4800 3700);
PAINT SKYBLUE (-4800 3700);
FORCEPROP 2 LAST VALUE 2.2UH
J 0
(-5225 3800);
DISPLAY 0.489362 (-5225 3800);
PAINT SKYBLUE (-5225 3800);
FORCEPROP 1 LAST PART_NUMBER CV-2280MZ15
J 0
(-5275 3700);
DISPLAY 0.489362 (-5275 3700);
PAINT SKYBLUE (-5275 3700);
FORCEPROP 2 LAST PACK_TYPE SMLF
J 0
(-4825 3800);
DISPLAY 0.489362 (-4825 3800);
PAINT SKYBLUE (-4825 3800);
FORCEPROP 2 LAST CDS_LIB pure_quanta
J 0
(-5000 3775);
DISPLAY INVISIBLE (-5000 3775);
FORCEPROP 1 LAST NEEDS_NO_SIZE TRUE
J 0
(-5000 3775);
DISPLAY 0.468085 (-5000 3775);
PAINT GREEN (-5000 3775);
DISPLAY INVISIBLE (-5000 3775);
FORCEPROP 1 LAST PATH I56
J 0
(-4925 3830);
DISPLAY 0.723404 (-4925 3830);
PAINT GREEN (-4925 3830);
DISPLAY INVISIBLE (-4925 3830);
FORCEADD UNIVERSAL_GND..1
(-8300 3375);
FORCEPROP 3 LASTPIN (-8300 3425) SIG_NAME GND\g
J 0
(-8290 3435);
DISPLAY 0.659574 (-8290 3435);
PAINT MONO (-8290 3435);
DISPLAY INVISIBLE (-8290 3435);
FORCEPROP 2 LAST CDS_LIB pure_quanta_power
J 0
(-8300 3375);
DISPLAY INVISIBLE (-8300 3375);
FORCEPROP 1 LAST PATH I57
J 0
(-8225 3375);
DISPLAY 0.872340 (-8225 3375);
PAINT AQUA (-8225 3375);
DISPLAY INVISIBLE (-8225 3375);
FORCEPROP 1 LAST HDL_POWER GND
J 1
(-8275 3300);
DISPLAY 0.872340 (-8275 3300);
PAINT GREEN (-8275 3300);
DISPLAY INVISIBLE (-8275 3300);
FORCEADD Q_CAP..1
R 2
(-8300 3575);
FORCEPROP 1 LAST LOCATION C348
J 2
(-8350 3675);
DISPLAY 0.489362 (-8350 3675);
PAINT SKYBLUE (-8350 3675);
FORCEPROP 0 LAST $SEC 1
J 0
(-8350 3725);
DISPLAY 0.680851 (-8350 3725);
PAINT MONO (-8350 3725);
DISPLAY INVISIBLE (-8350 3725);
FORCEPROP 0 LAST CDS_SEC 1
J 0
(-8350 3725);
DISPLAY 0.680851 (-8350 3725);
DISPLAY INVISIBLE (-8350 3725);
FORCEPROP 1 LASTPIN (-8300 3675) $PN 1
J 2
(-8310 3655);
DISPLAY 0.489362 (-8310 3655);
PAINT MONO (-8310 3655);
FORCEPROP 1 LASTPIN (-8300 3475) $PN 2
J 2
(-8310 3455);
DISPLAY 0.489362 (-8310 3455);
PAINT MONO (-8310 3455);
FORCEPROP 1 LAST MATERIAL EMPTY
J 2
(-8350 3475);
DISPLAY 0.489362 (-8350 3475);
PAINT RED (-8350 3475);
FORCEPROP 1 LAST TOLERANCE 10%
J 2
(-8350 3525);
DISPLAY 0.489362 (-8350 3525);
PAINT SKYBLUE (-8350 3525);
FORCEPROP 1 LAST VALUE 0.1UF
J 2
(-8350 3625);
DISPLAY 0.489362 (-8350 3625);
PAINT SKYBLUE (-8350 3625);
FORCEPROP 1 LAST PART_NUMBER CH4104K1B00
J 2
(-8375 3425);
DISPLAY 0.489362 (-8375 3425);
PAINT SKYBLUE (-8375 3425);
FORCEPROP 1 LAST VOLTAGE 25V
J 2
(-8350 3575);
DISPLAY 0.489362 (-8350 3575);
PAINT SKYBLUE (-8350 3575);
FORCEPROP 1 LAST PACK_TYPE 0402
J 2
(-8350 3375);
DISPLAY 0.489362 (-8350 3375);
PAINT SKYBLUE (-8350 3375);
FORCEPROP 2 LAST CDS_LIB pure_quanta
J 0
(-8300 3575);
DISPLAY INVISIBLE (-8300 3575);
FORCEPROP 1 LAST PATH I58
J 2
(-8350 3725);
DISPLAY 0.978723 (-8350 3725);
PAINT WHITE (-8350 3725);
DISPLAY INVISIBLE (-8350 3725);
FORCEPROP 2 LAST ROOM VR_DDR0_CTRL
R 3
J 1
(-8356 3536);
DISPLAY 0.744681 (-8356 3536);
PAINT RED (-8356 3536);
DISPLAY INVISIBLE (-8356 3536);
FORCEADD OFFPAGE..2
(-4000 4250);
FORCEPROP 2 LAST $XR0 80 
J 0
(-3811 4250);
DISPLAY 0.638298 (-3811 4250);
PAINT MONO (-3811 4250);
FORCEPROP 2 LAST PATH I59
J 0
(-3800 4300);
DISPLAY 0.680851 (-3800 4300);
DISPLAY INVISIBLE (-3800 4300);
FORCEPROP 1 LAST COMMENT_BODY TRUE
J 0
(-4045 4155);
DISPLAY 0.872340 (-4045 4155);
PAINT GREEN (-4045 4155);
DISPLAY INVISIBLE (-4045 4155);
FORCEPROP 1 LAST OFFPAGE TRUE
J 0
(-3675 4125);
DISPLAY 0.872340 (-3675 4125);
PAINT GREEN (-3675 4125);
DISPLAY INVISIBLE (-3675 4125);
FORCEPROP 2 LAST CDS_LIB standard
J 0
(-4000 4250);
DISPLAY INVISIBLE (-4000 4250);
FORCEADD Q_RES..1
(-5050 4250);
FORCEPROP 1 LAST LOCATION R225
J 0
(-4925 4250);
DISPLAY 0.489362 (-4925 4250);
PAINT SKYBLUE (-4925 4250);
FORCEPROP 0 LAST $SEC 1
J 0
(-4925 4300);
DISPLAY 0.680851 (-4925 4300);
PAINT MONO (-4925 4300);
DISPLAY INVISIBLE (-4925 4300);
FORCEPROP 0 LAST CDS_SEC 1
J 0
(-4925 4300);
DISPLAY 1.021277 (-4925 4300);
DISPLAY INVISIBLE (-4925 4300);
FORCEPROP 1 LASTPIN (-5150 4250) $PN 1
J 0
(-5138 4262);
DISPLAY 0.489362 (-5138 4262);
PAINT MONO (-5138 4262);
FORCEPROP 1 LASTPIN (-4950 4250) $PN 2
J 0
(-4988 4262);
DISPLAY 0.489362 (-4988 4262);
PAINT MONO (-4988 4262);
FORCEPROP 1 LAST VALUE 33
J 2
(-5175 4250);
DISPLAY 0.489362 (-5175 4250);
PAINT SKYBLUE (-5175 4250);
FORCEPROP 2 LAST CDS_LIB pure_quanta
J 2
(-5050 4250);
DISPLAY INVISIBLE (-5050 4250);
FORCEPROP 2 LAST BOM_COST MEM
J 2
(-5025 4400);
DISPLAY 0.744681 (-5025 4400);
PAINT WHITE (-5025 4400);
DISPLAY INVISIBLE (-5025 4400);
FORCEPROP 1 LAST PATH I60
J 0
(-5100 4400);
DISPLAY 0.978723 (-5100 4400);
PAINT WHITE (-5100 4400);
DISPLAY INVISIBLE (-5100 4400);
FORCEPROP 1 LAST WATTAGE 1/16W
J 2
(-5125 4175);
DISPLAY 0.489362 (-5125 4175);
PAINT SKYBLUE (-5125 4175);
DISPLAY INVISIBLE (-5125 4175);
FORCEPROP 1 LAST MATERIAL CHIP
J 2
(-4875 4225);
DISPLAY 0.489362 (-4875 4225);
PAINT SKYBLUE (-4875 4225);
DISPLAY INVISIBLE (-4875 4225);
FORCEPROP 1 LAST TOLERANCE 5%
J 0
(-5175 4225);
DISPLAY 0.489362 (-5175 4225);
PAINT SKYBLUE (-5175 4225);
DISPLAY INVISIBLE (-5175 4225);
FORCEPROP 1 LAST PART_NUMBER CS03302JB29
J 2
(-4950 4300);
DISPLAY 0.489362 (-4950 4300);
PAINT SKYBLUE (-4950 4300);
DISPLAY INVISIBLE (-4950 4300);
FORCEPROP 1 LAST PACK_TYPE 0402LF
J 2
(-4875 4175);
DISPLAY 0.489362 (-4875 4175);
PAINT SKYBLUE (-4875 4175);
DISPLAY INVISIBLE (-4875 4175);
FORCEPROP 2 LAST ROOM RST_CPU0_PLD_TO_DIMM
J 2
(-5025 4350);
DISPLAY 0.744681 (-5025 4350);
PAINT RED (-5025 4350);
DISPLAY INVISIBLE (-5025 4350);
FORCEADD Q_CAP..1
(-9000 4625);
FORCEPROP 1 LAST LOCATION PC119
J 0
(-8950 4725);
DISPLAY 0.489362 (-8950 4725);
PAINT SKYBLUE (-8950 4725);
FORCEPROP 2 LAST SEC 1
J 0
(-8950 4825);
DISPLAY 0.680851 (-8950 4825);
PAINT MONO (-8950 4825);
DISPLAY INVISIBLE (-8950 4825);
FORCEPROP 1 LASTPIN (-9000 4725) $PN 1
J 0
(-8990 4705);
DISPLAY 0.489362 (-8990 4705);
PAINT MONO (-8990 4705);
FORCEPROP 1 LASTPIN (-9000 4525) $PN 2
J 0
(-8990 4505);
DISPLAY 0.489362 (-8990 4505);
PAINT MONO (-8990 4505);
FORCEPROP 1 LAST MATERIAL X6S
J 0
(-8950 4525);
DISPLAY 0.489362 (-8950 4525);
PAINT SKYBLUE (-8950 4525);
FORCEPROP 1 LAST TOLERANCE 10%
J 0
(-8950 4575);
DISPLAY 0.489362 (-8950 4575);
PAINT SKYBLUE (-8950 4575);
FORCEPROP 1 LAST VALUE 10UF
J 0
(-8950 4675);
DISPLAY 0.489362 (-8950 4675);
PAINT SKYBLUE (-8950 4675);
FORCEPROP 1 LAST PART_NUMBER CH6104KEA00
J 0
(-8950 4475);
DISPLAY 0.489362 (-8950 4475);
PAINT SKYBLUE (-8950 4475);
FORCEPROP 1 LAST VOLTAGE 25V
J 0
(-8950 4625);
DISPLAY 0.489362 (-8950 4625);
PAINT SKYBLUE (-8950 4625);
FORCEPROP 1 LAST PACK_TYPE C0805
J 0
(-8950 4425);
DISPLAY 0.489362 (-8950 4425);
PAINT SKYBLUE (-8950 4425);
FORCEPROP 2 LAST SEC_TYPE C0805
J 0
(-8950 4825);
DISPLAY 1.021277 (-8950 4825);
DISPLAY INVISIBLE (-8950 4825);
FORCEPROP 2 LAST CDS_LIB pure_quanta
J 0
(-9000 4625);
DISPLAY INVISIBLE (-9000 4625);
FORCEPROP 1 LAST PATH I7
J 0
(-8950 4775);
DISPLAY 0.978723 (-8950 4775);
PAINT WHITE (-8950 4775);
DISPLAY INVISIBLE (-8950 4775);
FORCEADD Q_CAP..1
(-8500 4625);
FORCEPROP 1 LAST LOCATION PC120
J 0
(-8450 4725);
DISPLAY 0.489362 (-8450 4725);
PAINT SKYBLUE (-8450 4725);
FORCEPROP 0 LAST SEC 1
J 0
(-8450 4750);
DISPLAY 0.680851 (-8450 4750);
PAINT MONO (-8450 4750);
DISPLAY INVISIBLE (-8450 4750);
FORCEPROP 1 LASTPIN (-8500 4725) $PN 1
J 0
(-8490 4705);
DISPLAY 0.489362 (-8490 4705);
PAINT MONO (-8490 4705);
FORCEPROP 1 LASTPIN (-8500 4525) $PN 2
J 0
(-8490 4505);
DISPLAY 0.489362 (-8490 4505);
PAINT MONO (-8490 4505);
FORCEPROP 1 LAST MATERIAL X6S
J 0
(-8450 4525);
DISPLAY 0.489362 (-8450 4525);
PAINT SKYBLUE (-8450 4525);
FORCEPROP 1 LAST TOLERANCE 10%
J 0
(-8450 4575);
DISPLAY 0.489362 (-8450 4575);
PAINT SKYBLUE (-8450 4575);
FORCEPROP 1 LAST VALUE 10UF
J 0
(-8450 4675);
DISPLAY 0.489362 (-8450 4675);
PAINT SKYBLUE (-8450 4675);
FORCEPROP 1 LAST VOLTAGE 25V
J 0
(-8450 4625);
DISPLAY 0.489362 (-8450 4625);
PAINT SKYBLUE (-8450 4625);
FORCEPROP 1 LAST PACK_TYPE C0805
J 0
(-8450 4425);
DISPLAY 0.489362 (-8450 4425);
PAINT SKYBLUE (-8450 4425);
FORCEPROP 2 LAST SEC_TYPE C0805
J 0
(-8450 4825);
DISPLAY 1.021277 (-8450 4825);
DISPLAY INVISIBLE (-8450 4825);
FORCEPROP 2 LAST CDS_LIB pure_quanta
J 0
(-8500 4625);
DISPLAY INVISIBLE (-8500 4625);
FORCEPROP 1 LAST PATH I8
J 0
(-8450 4775);
DISPLAY 0.978723 (-8450 4775);
PAINT WHITE (-8450 4775);
DISPLAY INVISIBLE (-8450 4775);
FORCEPROP 1 LAST PART_NUMBER CH6104KEA00
J 0
(-8450 4475);
DISPLAY 0.978723 (-8450 4475);
PAINT SKYBLUE (-8450 4475);
DISPLAY INVISIBLE (-8450 4475);
FORCEADD Q_CAP..1
(-8100 4625);
FORCEPROP 1 LAST LOCATION PC123
J 0
(-8050 4725);
DISPLAY 0.489362 (-8050 4725);
PAINT SKYBLUE (-8050 4725);
FORCEPROP 0 LAST SEC 1
J 0
(-8050 4750);
DISPLAY 0.680851 (-8050 4750);
PAINT MONO (-8050 4750);
DISPLAY INVISIBLE (-8050 4750);
FORCEPROP 1 LASTPIN (-8100 4725) $PN 1
J 0
(-8090 4705);
DISPLAY 0.489362 (-8090 4705);
PAINT MONO (-8090 4705);
FORCEPROP 1 LASTPIN (-8100 4525) $PN 2
J 0
(-8090 4505);
DISPLAY 0.489362 (-8090 4505);
PAINT MONO (-8090 4505);
FORCEPROP 1 LAST MATERIAL X6S
J 0
(-8050 4525);
DISPLAY 0.489362 (-8050 4525);
PAINT SKYBLUE (-8050 4525);
FORCEPROP 1 LAST TOLERANCE 10%
J 0
(-8050 4575);
DISPLAY 0.489362 (-8050 4575);
PAINT SKYBLUE (-8050 4575);
FORCEPROP 1 LAST VALUE 10UF
J 0
(-8050 4675);
DISPLAY 0.489362 (-8050 4675);
PAINT SKYBLUE (-8050 4675);
FORCEPROP 1 LAST VOLTAGE 25V
J 0
(-8050 4625);
DISPLAY 0.489362 (-8050 4625);
PAINT SKYBLUE (-8050 4625);
FORCEPROP 1 LAST PACK_TYPE C0805
J 0
(-8050 4425);
DISPLAY 0.489362 (-8050 4425);
PAINT SKYBLUE (-8050 4425);
FORCEPROP 2 LAST SEC_TYPE C0805
J 0
(-8050 4825);
DISPLAY 1.021277 (-8050 4825);
DISPLAY INVISIBLE (-8050 4825);
FORCEPROP 2 LAST CDS_LIB pure_quanta
J 0
(-8100 4625);
DISPLAY INVISIBLE (-8100 4625);
FORCEPROP 1 LAST PATH I9
J 0
(-8050 4775);
DISPLAY 0.978723 (-8050 4775);
PAINT WHITE (-8050 4775);
DISPLAY INVISIBLE (-8050 4775);
FORCEPROP 1 LAST PART_NUMBER CH6104KEA00
J 0
(-8050 4475);
DISPLAY 0.978723 (-8050 4475);
PAINT SKYBLUE (-8050 4475);
DISPLAY INVISIBLE (-8050 4475);
FORCEADD QUANTA_TITLE_BLOCK_C..1
(-1675 425);
FORCEPROP 0 LAST CDS_CON_LAST_MODIFIED Fri Mar 11 14:53:22 2022
J 0
(-3560 440);
DISPLAY INVISIBLE (-3560 440);
FORCEPROP 1 LAST CUSTOM_TXT_CDS <CON_LAST_MODIFIED>
J 0
(-3560 440);
DISPLAY 0.978723 (-3560 440);
FORCEPROP 2 LAST CUSTOM_TXT_CDS <XR_PAGE_TITLE>
J 0
(-9565 5675);
DISPLAY 0.638298 (-9565 5675);
PAINT PINK (-9565 5675);
DISPLAY INVISIBLE (-9565 5675);
FORCEPROP 1 LAST CUSTOM_TXT_CDS <NAME_2>
J 0
(-4850 475);
FORCEPROP 1 LAST CUSTOM_TXT_CDS <NAME_1>
J 0
(-4850 600);
FORCEPROP 1 LAST CUSTOM_TXT_CDS <Q_NUMBER>
J 0
(-3078 528);
DISPLAY 1.212766 (-3078 528);
FORCEPROP 1 LAST CUSTOM_TXT_CDS <Q_PROJ>
J 0
(-4057 527);
DISPLAY 1.212766 (-4057 527);
FORCEPROP 1 LAST CUSTOM_TXT_CDS <Q_REV>
J 0
(-1859 528);
DISPLAY 1.212766 (-1859 528);
FORCEPROP 1 LAST CUSTOM_TXT_CDS <CON_PAGE_NUM> OF <CON_TOTAL_PAGES>
J 0
(-2121 443);
DISPLAY 0.978723 (-2121 443);
FORCEPROP 1 LAST Q_DEPT BU9
J 1
(-5438 474);
DISPLAY 1.957447 (-5438 474);
PAINT GREEN (-5438 474);
FORCEPROP 1 LAST Q_TITLE PVDD_33_S5
J 0
(-11041 451);
DISPLAY 2.446809 (-11041 451);
PAINT GREEN (-11041 451);
FORCEPROP 2 LAST PAGE_BORDER TRUE
J 0
(-9565 5675);
DISPLAY 0.638298 (-9565 5675);
PAINT PINK (-9565 5675);
DISPLAY INVISIBLE (-9565 5675);
FORCEPROP 1 LAST CDS_LMAN_SYM_OUTLINE -9475,6775,100,-125
J 0
(-1675 425);
DISPLAY 0.468085 (-1675 425);
PAINT GREEN (-1675 425);
DISPLAY INVISIBLE (-1675 425);
FORCEPROP 2 LAST CDS_LIB pure_quanta
J 0
(-1675 425);
DISPLAY INVISIBLE (-1675 425);
FORCEPROP 1 LAST COMMENT_BODY TRUE
J 0
(-1663 412);
DISPLAY 0.978723 (-1663 412);
PAINT GREEN (-1663 412);
DISPLAY INVISIBLE (-1663 412);
FORCEPROP 2 LAST CDS_XR_PAGE_TITLE CR-168 : @T6G_MB_LIB.T6G(SCH_1):PAGE168
J 0
(-9565 5675);
DISPLAY 0.638298 (-9565 5675);
PAINT PINK (-9565 5675);
DISPLAY INVISIBLE (-9565 5675);
FORCEADD DNS..1
(-8325 3475);
PAINT RED (-8325 3475);
FORCEPROP 2 LAST CDS_LIB mstr_misc
J 0
(-8325 3475);
DISPLAY INVISIBLE (-8325 3475);
FORCEPROP 1 LAST COMMENT_BODY TRUE
J 0
(-8325 3475);
DISPLAY INVISIBLE (-8325 3475);
WIRE 16 -1 (-6200 4700)(-6200 4850);
WIRE 16 -1 (-7700 2500)(-7700 2625);
WIRE 16 -1 (-5950 2800)(-5950 2750);
WIRE 16 -1 (-5600 3150)(-5600 2750);
WIRE 16 -1 (-6300 3150)(-5600 3150);
WIRE 16 -1 (-5000 2325)(-5000 2450);
WIRE 16 -1 (-8275 2425)(-8275 2550);
WIRE 16 -1 (-8300 3425)(-8300 3475);
WIRE 17 273 (-10625 1500)(-8450 1500);
WIRE 17 273 (-10625 1500)(-10625 900);
WIRE 17 273 (-8450 1500)(-8450 900);
WIRE 17 273 (-10625 900)(-8450 900);
WIRE 17 273 (-10625 1650)(-8450 1650);
WIRE 17 273 (-10625 2050)(-10625 1650);
WIRE 17 273 (-8450 2050)(-8450 1650);
WIRE 17 273 (-10625 2050)(-8450 2050);
WIRE 16 -1 (-9800 4950)(-9800 4800);
WIRE 16 -1 (-9800 4800)(-9500 4800);
WIRE 16 -1 (-9300 4800)(-9000 4800);
WIRE 16 -1 (-8500 4800)(-9000 4800);
WIRE 16 -1 (-9000 4800)(-9000 4725);
WIRE 16 -1 (-8500 4800)(-8100 4800);
FORCEPROP 2 LAST SIG_NAME SW_P12V_STBY_PVDD_33_S5_FLT
J 0
(-8485 4810);
DISPLAY 0.489362 (-8485 4810);
FORCEPROP 2 LASTPROP $XRERR UNIQUE?
J 0
(-8725 4810);
DISPLAY 0.638298 (-8725 4810);
PAINT MONO (-8725 4810);
DISPLAY INVISIBLE (-8725 4810);
WIRE 16 -1 (-8500 4725)(-8500 4800);
WIRE 16 -1 (-7700 4800)(-8100 4800);
WIRE 16 -1 (-8100 4800)(-8100 4725);
WIRE 16 -1 (-7200 4800)(-7700 4800);
WIRE 16 -1 (-7700 4725)(-7700 4800);
WIRE 16 -1 (-7200 4250)(-7200 4800);
WIRE 16 -1 (-7100 4250)(-7200 4250);
WIRE 16 -1 (-7200 4200)(-7200 4250);
WIRE 16 -1 (-7100 4200)(-7200 4200);
WIRE 16 -1 (-8500 4400)(-9000 4400);
WIRE 16 -1 (-8500 4400)(-8100 4400);
WIRE 16 -1 (-8500 4525)(-8500 4400);
WIRE 16 -1 (-9000 4525)(-9000 4400);
WIRE 16 -1 (-9000 4400)(-9000 4300);
WIRE 16 -1 (-7700 4400)(-8100 4400);
WIRE 16 -1 (-8100 4525)(-8100 4400);
WIRE 16 -1 (-7700 4525)(-7700 4400);
WIRE 16 -1 (-8550 3750)(-8300 3750);
WIRE 16 -1 (-8300 3750)(-7100 3750);
FORCEPROP 2 LAST SIG_NAME PVDD33_S5_EN
J 0
(-8200 3760);
DISPLAY 0.489362 (-8200 3760);
WIRE 16 -1 (-8300 3750)(-8300 3675);
WIRE 16 -1 (-8275 2750)(-8275 2975);
WIRE 16 -1 (-8275 2975)(-7975 2975);
WIRE 16 -1 (-8275 3150)(-8275 2975);
WIRE 16 -1 (-7975 2975)(-7975 3300);
WIRE 16 -1 (-7100 3300)(-7975 3300);
WIRE 16 -1 (-7975 3300)(-7975 3550);
WIRE 16 -1 (-7100 3550)(-7975 3550);
WIRE 16 -1 (-7100 2950)(-7700 2950);
FORCEPROP 2 LAST SIG_NAME PVDD_33_S5_CS
J 0
(-7510 2960);
DISPLAY 0.489362 (-7510 2960);
FORCEPROP 2 LASTPROP $XRERR UNIQUE?
J 0
(-7750 2960);
DISPLAY 0.638298 (-7750 2960);
PAINT MONO (-7750 2960);
DISPLAY INVISIBLE (-7750 2960);
WIRE 16 -1 (-7700 2950)(-7700 2825);
WIRE 16 -1 (-6200 2750)(-6200 2900);
WIRE 16 -1 (-6200 2950)(-6200 2900);
WIRE 16 -1 (-6200 2900)(-6300 2900);
WIRE 16 -1 (-6300 2950)(-6200 2950);
WIRE 16 -1 (-5950 3000)(-5950 3050);
WIRE 16 -1 (-5950 3050)(-6300 3050);
FORCEPROP 2 LAST SIG_NAME PVDD_33_S5_REF
J 0
(-6235 3060);
DISPLAY 0.489362 (-6235 3060);
FORCEPROP 2 LASTPROP $XRERR UNIQUE?
J 0
(-6475 3060);
DISPLAY 0.638298 (-6475 3060);
PAINT MONO (-6475 3060);
DISPLAY INVISIBLE (-6475 3060);
WIRE 16 -1 (-5250 2800)(-5250 3300);
WIRE 16 -1 (-5000 2800)(-5250 2800);
WIRE 16 -1 (-5250 3300)(-6300 3300);
FORCEPROP 2 LAST SIG_NAME PVDD_33_S5_FB
J 0
(-6235 3310);
DISPLAY 0.489362 (-6235 3310);
FORCEPROP 2 LASTPROP $XRERR UNIQUE?
J 0
(-6475 3310);
DISPLAY 0.638298 (-6475 3310);
PAINT MONO (-6475 3310);
DISPLAY INVISIBLE (-6475 3310);
WIRE 16 -1 (-4500 2800)(-5000 2800);
WIRE 16 -1 (-5000 2800)(-5000 2650);
WIRE 16 -1 (-4150 2800)(-4500 2800);
WIRE 16 -1 (-4500 2800)(-4500 2400);
WIRE 16 -1 (-4150 2400)(-4500 2400);
WIRE 16 -1 (-5600 4000)(-5600 4050);
WIRE 16 -1 (-5600 4050)(-6300 4050);
FORCEPROP 2 LAST SIG_NAME SW_PVDD_33_S5_BST
J 0
(-6235 4060);
DISPLAY 0.489362 (-6235 4060);
FORCEPROP 2 LASTPROP $XRERR UNIQUE?
J 0
(-6475 4060);
DISPLAY 0.638298 (-6475 4060);
PAINT MONO (-6475 4060);
DISPLAY INVISIBLE (-6475 4060);
WIRE 16 -1 (-6300 3750)(-5600 3750);
FORCEPROP 2 LAST SIG_NAME SW_PVDD_33_S5_SW
J 0
(-6235 3760);
DISPLAY 0.489362 (-6235 3760);
FORCEPROP 2 LASTPROP $XRERR UNIQUE?
J 0
(-6475 3760);
DISPLAY 0.638298 (-6475 3760);
PAINT MONO (-6475 3760);
DISPLAY INVISIBLE (-6475 3760);
WIRE 16 -1 (-5100 3750)(-5600 3750);
WIRE 16 -1 (-5600 3800)(-5600 3750);
WIRE 16 -1 (-4400 3350)(-4400 3150);
WIRE 16 -1 (-4400 3150)(-4100 3150);
WIRE 16 -1 (-4100 3150)(-3800 3150);
WIRE 16 -1 (-4100 3350)(-4100 3150);
WIRE 16 -1 (-3800 3150)(-3500 3150);
WIRE 16 -1 (-3800 3350)(-3800 3150);
WIRE 16 -1 (-3500 3150)(-3100 3150);
WIRE 16 -1 (-3500 3350)(-3500 3150);
WIRE 16 -1 (-3100 3350)(-3100 3150);
WIRE 16 -1 (-3100 3150)(-3100 3100);
WIRE 16 -1 (-4900 3750)(-4400 3750);
WIRE 16 -1 (-4400 3750)(-4100 3750);
WIRE 16 -1 (-4400 3550)(-4400 3750);
WIRE 16 -1 (-4100 3550)(-4100 3750);
WIRE 16 -1 (-4100 3750)(-3800 3750);
WIRE 16 -1 (-3800 3750)(-3500 3750);
WIRE 16 -1 (-3800 3550)(-3800 3750);
WIRE 16 -1 (-3100 3750)(-3500 3750);
WIRE 16 -1 (-3500 3550)(-3500 3750);
WIRE 16 -1 (-3100 3550)(-3100 3750);
WIRE 16 -1 (-2650 3750)(-3100 3750);
WIRE 16 -1 (-2650 3850)(-2650 3750);
WIRE 16 -1 (-2650 2800)(-2650 3750);
WIRE 16 -1 (-3600 2800)(-2650 2800);
WIRE 16 -1 (-3950 2800)(-3600 2800);
WIRE 16 -1 (-3600 2800)(-3600 2400);
WIRE 16 -1 (-3950 2400)(-3600 2400);
WIRE 16 -1 (-6300 4250)(-6200 4250);
WIRE 16 -1 (-5150 4250)(-6200 4250);
FORCEPROP 2 LAST SIG_NAME PWRGD_PVDD33_S5
J 0
(-5850 4260);
DISPLAY 0.489362 (-5850 4260);
FORCEPROP 2 LASTPROP $XRERR UNIQUE?
J 0
(-6090 4260);
DISPLAY 0.638298 (-6090 4260);
PAINT MONO (-6090 4260);
DISPLAY INVISIBLE (-6090 4260);
WIRE 16 -1 (-6200 4250)(-6200 4500);
WIRE 16 -1 (-4050 4250)(-4950 4250);
FORCEPROP 2 LAST SIG_NAME FM_PWRGD_PVDD33_S5
J 0
(-4775 4250);
DISPLAY 0.489362 (-4775 4250);
WIRE 17 273 (-3600 7000)(-1800 7000);
WIRE 17 273 (-3600 7000)(-3600 5900);
WIRE 17 273 (-1800 7000)(-1800 5900);
WIRE 17 273 (-3600 5900)(-1800 5900);
DOT 1 (-8300 3750);
DOT 1 (-8275 2975);
DOT 1 (-7975 3300);
DOT 1 (-6200 2900);
DOT 1 (-7200 4250);
DOT 1 (-8500 4400);
DOT 1 (-8100 4800);
DOT 1 (-9000 4800);
DOT 1 (-3800 3750);
DOT 1 (-8500 4800);
DOT 1 (-8100 4400);
DOT 1 (-4400 3750);
DOT 1 (-5600 3750);
DOT 1 (-7700 4800);
DOT 1 (-4100 3150);
DOT 1 (-3600 2800);
DOT 1 (-3800 3150);
DOT 1 (-5000 2800);
DOT 1 (-3500 3150);
DOT 1 (-3100 3150);
DOT 1 (-3500 3750);
DOT 1 (-3100 3750);
DOT 1 (-2650 3750);
DOT 1 (-4100 3750);
DOT 1 (-6200 4250);
DOT 1 (-9000 4400);
DOT 1 (-4500 2800);
FORCENOTE
2ND SOURCE:PC126 CHANGE TO CH5103KEB02
(-10550 1150) 0;
DISPLAY LEFT (-10550 1150);
DISPLAY 1.021277 (-10550 1150);
PAINT WHITE (-10550 1150);
FORCENOTE
MAIN SOURCE:
(-10550 1250) 0;
DISPLAY LEFT (-10550 1250);
DISPLAY 1.021277 (-10550 1250);
PAINT WHITE (-10550 1250);
FORCENOTE
BOM CHANGE
(-10550 1400) 0;
DISPLAY LEFT (-10550 1400);
DISPLAY 1.276596 (-10550 1400);
PAINT WHITE (-10550 1400);
FORCENOTE
2ND SOURCE:AL000548006/TPS548A28RWWR
(-10550 1700) 0;
DISPLAY LEFT (-10550 1700);
DISPLAY 1.021277 (-10550 1700);
PAINT WHITE (-10550 1700);
FORCENOTE
MAIN SOURCE:AL008633007/MPQ8633AGLE-C807-Z
(-10550 1800) 0;
DISPLAY LEFT (-10550 1800);
DISPLAY 1.021277 (-10550 1800);
PAINT WHITE (-10550 1800);
FORCENOTE
PC136 CHANGE TO CH13306JB14
(-10025 1050) 0;
DISPLAY LEFT (-10025 1050);
DISPLAY 1.021277 (-10025 1050);
PAINT WHITE (-10025 1050);
FORCENOTE
PVDD_33_S5 SPECIFICATION
(-3500 6850) 0;
DISPLAY LEFT (-3500 6850);
DISPLAY 1.468085 (-3500 6850);
PAINT WHITE (-3500 6850);
FORCENOTE
OUTPUT VOLTAGE=3.3V +/-5%
(-3500 6725) 0;
DISPLAY LEFT (-3500 6725);
DISPLAY 1.170213 (-3500 6725);
PAINT WHITE (-3500 6725);
FORCENOTE
OUTPUT RIPPLE & NOISE +/-1%
(-3500 6639) 0;
DISPLAY LEFT (-3500 6639);
DISPLAY 1.170213 (-3500 6639);
PAINT WHITE (-3500 6639);
FORCENOTE
DC & AC=3.13-3.46V
(-3500 6556) 0;
DISPLAY LEFT (-3500 6556);
DISPLAY 1.170213 (-3500 6556);
PAINT WHITE (-3500 6556);
FORCENOTE
TDC=6A
(-3500 6475) 0;
DISPLAY LEFT (-3500 6475);
DISPLAY 1.170213 (-3500 6475);
PAINT WHITE (-3500 6475);
FORCENOTE
FSW=600KHZ
(-9075 2375) 0;
DISPLAY LEFT (-9075 2375);
DISPLAY 1.276596 (-9075 2375);
PAINT WHITE (-9075 2375);
FORCENOTE
BOM NOTE
(-10550 1950) 0;
DISPLAY LEFT (-10550 1950);
DISPLAY 1.276596 (-10550 1950);
PAINT WHITE (-10550 1950);
FORCENOTE
VOUT=0.6(1+RA/RB)=3.3V
(-5875 2025) 0;
DISPLAY LEFT (-5875 2025);
DISPLAY 1.595745 (-5875 2025);
PAINT WHITE (-5875 2025);
FORCENOTE
RA
(-4150 2950) 0;
DISPLAY LEFT (-4150 2950);
DISPLAY 1.021277 (-4150 2950);
PAINT WHITE (-4150 2950);
FORCENOTE
RB
(-5125 2550) 0;
DISPLAY LEFT (-5125 2550);
DISPLAY 1.021277 (-5125 2550);
PAINT WHITE (-5125 2550);
FORCENOTE
EFFICENCY>90%@TDC
(-3500 5987) 0;
DISPLAY LEFT (-3500 5987);
DISPLAY 1.170213 (-3500 5987);
PAINT WHITE (-3500 5987);
FORCENOTE
SLEW RATE=2.5A/US
(-3500 6157) 0;
DISPLAY LEFT (-3500 6157);
DISPLAY 1.170213 (-3500 6157);
PAINT WHITE (-3500 6157);
FORCENOTE
CURRENT STEP=2A
(-3500 6232) 0;
DISPLAY LEFT (-3500 6232);
DISPLAY 1.170213 (-3500 6232);
PAINT WHITE (-3500 6232);
FORCENOTE
EDC=7.2A
(-3500 6382) 0;
DISPLAY LEFT (-3500 6382);
DISPLAY 1.170213 (-3500 6382);
PAINT WHITE (-3500 6382);
FORCENOTE
OVER CURRENT PROTECTION=9A
(-3500 6307) 0;
DISPLAY LEFT (-3500 6307);
DISPLAY 1.170213 (-3500 6307);
PAINT WHITE (-3500 6307);
FORCENOTE
WORK FREQUENCY=600KHZ
(-3500 6075) 0;
DISPLAY LEFT (-3500 6075);
DISPLAY 1.276596 (-3500 6075);
PAINT WHITE (-3500 6075);
FORCENOTE
PVDD_33_S5
(-7750 5675) 0;
DISPLAY LEFT (-7750 5675);
DISPLAY 4.914894 (-7750 5675);
PAINT WHITE (-7750 5675);
FORCENOTE
IRATED=5A@125C
(-9675 4725) 0;
DISPLAY LEFT (-9675 4725);
DISPLAY 0.808511 (-9675 4725);
PAINT WHITE (-9675 4725);
FORCENOTE
DCR=5M OHM
(-9675 4675) 0;
DISPLAY LEFT (-9675 4675);
DISPLAY 0.808511 (-9675 4675);
PAINT WHITE (-9675 4675);
FORCENOTE
2ND=CX220Z06Z00
(-9675 4625) 0;
DISPLAY LEFT (-9675 4625);
DISPLAY 0.808511 (-9675 4625);
PAINT WHITE (-9675 4625);
FORCENOTE
IDC=14A
(-5200 3450) 0;
DISPLAY LEFT (-5200 3450);
DISPLAY 1.021277 (-5200 3450);
PAINT WHITE (-5200 3450);
FORCENOTE
ISAT=8A@100C
(-5200 3525) 0;
DISPLAY LEFT (-5200 3525);
DISPLAY 1.021277 (-5200 3525);
PAINT WHITE (-5200 3525);
FORCENOTE
DCR=18MOHM 
(-5200 3600) 0;
DISPLAY LEFT (-5200 3600);
DISPLAY 1.021277 (-5200 3600);
PAINT WHITE (-5200 3600);
FORCENOTE
3RD=CX000220000
(-9675 4575) 0;
DISPLAY LEFT (-9675 4575);
DISPLAY 0.808511 (-9675 4575);
PAINT WHITE (-9675 4575);
FORCENOTE
PCMB063T-2R2MS
(-5200 3375) 0;
DISPLAY LEFT (-5200 3375);
DISPLAY 1.021277 (-5200 3375);
PAINT WHITE (-5200 3375);
FORCENOTE
6.5*6.9*3
(-5200 3300) 0;
DISPLAY LEFT (-5200 3300);
DISPLAY 1.021277 (-5200 3300);
PAINT WHITE (-5200 3300);
FORCENOTE
2ND=CV-2280MZ05
(-5200 3225) 0;
DISPLAY LEFT (-5200 3225);
DISPLAY 1.021277 (-5200 3225);
PAINT WHITE (-5200 3225);
QUIT
